(kicad_pcb
	(version 20260206)
	(generator "pcbnew")
	(generator_version "10.0")
	(general
		(thickness 1.6)
		(legacy_teardrops no)
	)
	(paper "A4")
	(title_block
		(title "04192023_DAF0TMB3IC0_F0TG_MB_C_brd_V02_OCP.brd")
		(comment 1 "Grand Teton / footprint 34 of 8354 (J37), pads 114-226 of 291")
	)
	(layers
		(0 "F.Cu" signal "TOP")
		(4 "In1.Cu" signal "GND")
		(6 "In2.Cu" signal "IN1")
		(8 "In3.Cu" signal "GND1")
		(10 "In4.Cu" signal "IN2")
		(12 "In5.Cu" signal "GND2")
		(14 "In6.Cu" signal "IN3")
		(16 "In7.Cu" signal "GND3")
		(18 "In8.Cu" signal "VCC")
		(20 "In9.Cu" signal "VCC1")
		(22 "In10.Cu" signal "GND4")
		(24 "In11.Cu" signal "IN4")
		(26 "In12.Cu" signal "GND5")
		(28 "In13.Cu" signal "IN5")
		(30 "In14.Cu" signal "GND6")
		(32 "In15.Cu" signal "IN6")
		(34 "In16.Cu" signal "GND7")
		(2 "B.Cu" signal "BOTTOM")
		(9 "F.Adhes" user "F.Adhesive")
		(11 "B.Adhes" user "B.Adhesive")
		(13 "F.Paste" user "Package Geometry/Pastemask Top")
		(15 "B.Paste" user "Package Geometry/Pastemask Bottom")
		(5 "F.SilkS" user "Ref Des/Silkscreen Top")
		(7 "B.SilkS" user "Ref Des/Silkscreen Bottom")
		(1 "F.Mask" user "Board Geometry/Soldermask Top")
		(3 "B.Mask" user "Board Geometry/Soldermask Bottom")
		(17 "Dwgs.User" user "User.Drawings")
		(19 "Cmts.User" user "User.Comments")
		(21 "Eco1.User" user "User.Eco1")
		(23 "Eco2.User" user "User.Eco2")
		(25 "Edge.Cuts" user "Board Geometry/Outline")
		(27 "Margin" user)
		(31 "F.CrtYd" user "Package Geometry/Place Bound Top")
		(29 "B.CrtYd" user "Package Geometry/Place Bound Bottom")
		(35 "F.Fab" user "Ref Des/Assembly Top")
		(33 "B.Fab" user "Ref Des/Assembly Bottom")
	)
	(footprint ""
		(layer "F.Cu")
		(at 204.197966 -255.560322 180)
		(property "Reference" "J37"
			(at 2.8702 -81.730088 0)
			(unlocked yes)
			(layer "F.SilkS")
			(effects
				(font
					(size 0.7874 0.5842)
					(thickness 0.1524)
				)
			)
		)
		(property "Value" ""
			(at 0 0 180)
			(layer "F.Fab")
			(effects
				(font
					(size 1.27 1.27)
				)
			)
		)
		(duplicate_pad_numbers_are_jumpers no)
		(pad "114" smd rect
			(at -2.050034 37.824918 90)
			(size 0.519938 1.4986)
			(layers "F.Cu" "F.Mask" "F.Paste")
			(net "GND")
		)
		(pad "115" smd rect
			(at -2.050034 38.675056 90)
			(size 0.519938 1.4986)
			(layers "F.Cu" "F.Mask" "F.Paste")
			(net "M_L_CPU1_SB_DQS_DP<1>")
		)
		(pad "116" smd rect
			(at -2.050034 39.52494 90)
			(size 0.519938 1.4986)
			(layers "F.Cu" "F.Mask" "F.Paste")
			(net "M_L_CPU1_SB_DQS_DN<1>")
		)
		(pad "117" smd rect
			(at -2.050034 40.375078 90)
			(size 0.519938 1.4986)
			(layers "F.Cu" "F.Mask" "F.Paste")
			(net "GND")
		)
		(pad "118" smd rect
			(at -2.050034 41.224962 90)
			(size 0.519938 1.4986)
			(layers "F.Cu" "F.Mask" "F.Paste")
			(net "M_L_CPU1_SB_DQ<12>")
		)
		(pad "119" smd rect
			(at -2.050034 42.0751 90)
			(size 0.519938 1.4986)
			(layers "F.Cu" "F.Mask" "F.Paste")
			(net "GND")
		)
		(pad "120" smd rect
			(at -2.050034 42.924984 90)
			(size 0.519938 1.4986)
			(layers "F.Cu" "F.Mask" "F.Paste")
			(net "M_L_CPU1_SB_DQ<13>")
		)
		(pad "121" smd rect
			(at -2.050034 43.775122 90)
			(size 0.519938 1.4986)
			(layers "F.Cu" "F.Mask" "F.Paste")
			(net "GND")
		)
		(pad "122" smd rect
			(at -2.050034 44.625006 90)
			(size 0.519938 1.4986)
			(layers "F.Cu" "F.Mask" "F.Paste")
			(net "M_L_CPU1_SB_DQ<16>")
		)
		(pad "123" smd rect
			(at -2.050034 45.47489 90)
			(size 0.519938 1.4986)
			(layers "F.Cu" "F.Mask" "F.Paste")
			(net "GND")
		)
		(pad "124" smd rect
			(at -2.050034 46.325028 90)
			(size 0.519938 1.4986)
			(layers "F.Cu" "F.Mask" "F.Paste")
			(net "M_L_CPU1_SB_DQ<17>")
		)
		(pad "125" smd rect
			(at -2.050034 47.174912 90)
			(size 0.519938 1.4986)
			(layers "F.Cu" "F.Mask" "F.Paste")
			(net "GND")
		)
		(pad "126" smd rect
			(at -2.050034 48.02505 90)
			(size 0.519938 1.4986)
			(layers "F.Cu" "F.Mask" "F.Paste")
			(net "M_L_CPU1_SB_DQS_DP<2>")
		)
		(pad "127" smd rect
			(at -2.050034 48.874934 90)
			(size 0.519938 1.4986)
			(layers "F.Cu" "F.Mask" "F.Paste")
			(net "M_L_CPU1_SB_DQS_DN<2>")
		)
		(pad "128" smd rect
			(at -2.050034 49.725072 90)
			(size 0.519938 1.4986)
			(layers "F.Cu" "F.Mask" "F.Paste")
			(net "GND")
		)
		(pad "129" smd rect
			(at -2.050034 50.574956 90)
			(size 0.519938 1.4986)
			(layers "F.Cu" "F.Mask" "F.Paste")
			(net "M_L_CPU1_SB_DQ<20>")
		)
		(pad "130" smd rect
			(at -2.050034 51.425094 90)
			(size 0.519938 1.4986)
			(layers "F.Cu" "F.Mask" "F.Paste")
			(net "GND")
		)
		(pad "131" smd rect
			(at -2.050034 52.274978 90)
			(size 0.519938 1.4986)
			(layers "F.Cu" "F.Mask" "F.Paste")
			(net "M_L_CPU1_SB_DQ<21>")
		)
		(pad "132" smd rect
			(at -2.050034 53.125116 90)
			(size 0.519938 1.4986)
			(layers "F.Cu" "F.Mask" "F.Paste")
			(net "GND")
		)
		(pad "133" smd rect
			(at -2.050034 53.975 90)
			(size 0.519938 1.4986)
			(layers "F.Cu" "F.Mask" "F.Paste")
			(net "M_L_CPU1_SB_DQ<24>")
		)
		(pad "134" smd rect
			(at -2.050034 54.824884 90)
			(size 0.519938 1.4986)
			(layers "F.Cu" "F.Mask" "F.Paste")
			(net "GND")
		)
		(pad "135" smd rect
			(at -2.050034 55.675022 90)
			(size 0.519938 1.4986)
			(layers "F.Cu" "F.Mask" "F.Paste")
			(net "M_L_CPU1_SB_DQ<25>")
		)
		(pad "136" smd rect
			(at -2.050034 56.524906 90)
			(size 0.519938 1.4986)
			(layers "F.Cu" "F.Mask" "F.Paste")
			(net "GND")
		)
		(pad "137" smd rect
			(at -2.050034 57.375044 90)
			(size 0.519938 1.4986)
			(layers "F.Cu" "F.Mask" "F.Paste")
			(net "M_L_CPU1_SB_DQS_DP<3>")
		)
		(pad "138" smd rect
			(at -2.050034 58.224928 90)
			(size 0.519938 1.4986)
			(layers "F.Cu" "F.Mask" "F.Paste")
			(net "M_L_CPU1_SB_DQS_DN<3>")
		)
		(pad "139" smd rect
			(at -2.050034 59.075066 90)
			(size 0.519938 1.4986)
			(layers "F.Cu" "F.Mask" "F.Paste")
			(net "GND")
		)
		(pad "140" smd rect
			(at -2.050034 59.92495 90)
			(size 0.519938 1.4986)
			(layers "F.Cu" "F.Mask" "F.Paste")
			(net "M_L_CPU1_SB_DQ<28>")
		)
		(pad "141" smd rect
			(at -2.050034 60.775088 90)
			(size 0.519938 1.4986)
			(layers "F.Cu" "F.Mask" "F.Paste")
			(net "GND")
		)
		(pad "142" smd rect
			(at -2.050034 61.624972 90)
			(size 0.519938 1.4986)
			(layers "F.Cu" "F.Mask" "F.Paste")
			(net "M_L_CPU1_SB_DQ<29>")
		)
		(pad "143" smd rect
			(at -2.050034 62.47511 90)
			(size 0.519938 1.4986)
			(layers "F.Cu" "F.Mask" "F.Paste")
			(net "GND")
		)
		(pad "144" smd rect
			(at -2.050034 63.324994 90)
			(size 0.519938 1.4986)
			(layers "F.Cu" "F.Mask" "F.Paste")
			(net "Net_2411")
		)
		(pad "145" smd rect
			(at 2.050034 -63.324994 90)
			(size 0.519938 1.4986)
			(layers "F.Cu" "F.Mask" "F.Paste")
			(net "P12V_MEM_CPU1")
		)
		(pad "146" smd rect
			(at 2.050034 -62.47511 90)
			(size 0.519938 1.4986)
			(layers "F.Cu" "F.Mask" "F.Paste")
			(net "P12V_MEM_CPU1")
		)
		(pad "147" smd rect
			(at 2.050034 -61.624972 90)
			(size 0.519938 1.4986)
			(layers "F.Cu" "F.Mask" "F.Paste")
			(net "PWRGD_CHL_CPU1_DIMM")
		)
		(pad "148" smd rect
			(at 2.050034 -60.775088 90)
			(size 0.519938 1.4986)
			(layers "F.Cu" "F.Mask" "F.Paste")
			(net "PD_CHL_CPU1_DIMM_SAA")
		)
		(pad "149" smd rect
			(at 2.050034 -59.92495 90)
			(size 0.519938 1.4986)
			(layers "F.Cu" "F.Mask" "F.Paste")
			(net "Net_2412")
		)
		(pad "150" smd rect
			(at 2.050034 -59.075066 90)
			(size 0.519938 1.4986)
			(layers "F.Cu" "F.Mask" "F.Paste")
			(net "Net_2413")
		)
		(pad "151" smd rect
			(at 2.050034 -58.224928 90)
			(size 0.519938 1.4986)
			(layers "F.Cu" "F.Mask" "F.Paste")
			(net "GND")
		)
		(pad "152" smd rect
			(at 2.050034 -57.375044 90)
			(size 0.519938 1.4986)
			(layers "F.Cu" "F.Mask" "F.Paste")
			(net "M_L_CPU1_SA_DQ<2>")
		)
		(pad "153" smd rect
			(at 2.050034 -56.524906 90)
			(size 0.519938 1.4986)
			(layers "F.Cu" "F.Mask" "F.Paste")
			(net "GND")
		)
		(pad "154" smd rect
			(at 2.050034 -55.675022 90)
			(size 0.519938 1.4986)
			(layers "F.Cu" "F.Mask" "F.Paste")
			(net "M_L_CPU1_SA_DQ<3>")
		)
		(pad "155" smd rect
			(at 2.050034 -54.824884 90)
			(size 0.519938 1.4986)
			(layers "F.Cu" "F.Mask" "F.Paste")
			(net "GND")
		)
		(pad "156" smd rect
			(at 2.050034 -53.975 90)
			(size 0.519938 1.4986)
			(layers "F.Cu" "F.Mask" "F.Paste")
			(net "M_L_CPU1_SA_DQS_DN<5>")
		)
		(pad "157" smd rect
			(at 2.050034 -53.125116 90)
			(size 0.519938 1.4986)
			(layers "F.Cu" "F.Mask" "F.Paste")
			(net "M_L_CPU1_SA_DQS_DP<5>")
		)
		(pad "158" smd rect
			(at 2.050034 -52.274978 90)
			(size 0.519938 1.4986)
			(layers "F.Cu" "F.Mask" "F.Paste")
			(net "GND")
		)
		(pad "159" smd rect
			(at 2.050034 -51.425094 90)
			(size 0.519938 1.4986)
			(layers "F.Cu" "F.Mask" "F.Paste")
			(net "M_L_CPU1_SA_DQ<6>")
		)
		(pad "160" smd rect
			(at 2.050034 -50.574956 90)
			(size 0.519938 1.4986)
			(layers "F.Cu" "F.Mask" "F.Paste")
			(net "GND")
		)
		(pad "161" smd rect
			(at 2.050034 -49.725072 90)
			(size 0.519938 1.4986)
			(layers "F.Cu" "F.Mask" "F.Paste")
			(net "M_L_CPU1_SA_DQ<7>")
		)
		(pad "162" smd rect
			(at 2.050034 -48.874934 90)
			(size 0.519938 1.4986)
			(layers "F.Cu" "F.Mask" "F.Paste")
			(net "GND")
		)
		(pad "163" smd rect
			(at 2.050034 -48.02505 90)
			(size 0.519938 1.4986)
			(layers "F.Cu" "F.Mask" "F.Paste")
			(net "M_L_CPU1_SA_DQ<10>")
		)
		(pad "164" smd rect
			(at 2.050034 -47.174912 90)
			(size 0.519938 1.4986)
			(layers "F.Cu" "F.Mask" "F.Paste")
			(net "GND")
		)
		(pad "165" smd rect
			(at 2.050034 -46.325028 90)
			(size 0.519938 1.4986)
			(layers "F.Cu" "F.Mask" "F.Paste")
			(net "M_L_CPU1_SA_DQ<11>")
		)
		(pad "166" smd rect
			(at 2.050034 -45.47489 90)
			(size 0.519938 1.4986)
			(layers "F.Cu" "F.Mask" "F.Paste")
			(net "GND")
		)
		(pad "167" smd rect
			(at 2.050034 -44.625006 90)
			(size 0.519938 1.4986)
			(layers "F.Cu" "F.Mask" "F.Paste")
			(net "M_L_CPU1_SA_DQS_DN<6>")
		)
		(pad "168" smd rect
			(at 2.050034 -43.775122 90)
			(size 0.519938 1.4986)
			(layers "F.Cu" "F.Mask" "F.Paste")
			(net "M_L_CPU1_SA_DQS_DP<6>")
		)
		(pad "169" smd rect
			(at 2.050034 -42.924984 90)
			(size 0.519938 1.4986)
			(layers "F.Cu" "F.Mask" "F.Paste")
			(net "GND")
		)
		(pad "170" smd rect
			(at 2.050034 -42.0751 90)
			(size 0.519938 1.4986)
			(layers "F.Cu" "F.Mask" "F.Paste")
			(net "M_L_CPU1_SA_DQ<14>")
		)
		(pad "171" smd rect
			(at 2.050034 -41.224962 90)
			(size 0.519938 1.4986)
			(layers "F.Cu" "F.Mask" "F.Paste")
			(net "GND")
		)
		(pad "172" smd rect
			(at 2.050034 -40.375078 90)
			(size 0.519938 1.4986)
			(layers "F.Cu" "F.Mask" "F.Paste")
			(net "M_L_CPU1_SA_DQ<15>")
		)
		(pad "173" smd rect
			(at 2.050034 -39.52494 90)
			(size 0.519938 1.4986)
			(layers "F.Cu" "F.Mask" "F.Paste")
			(net "GND")
		)
		(pad "174" smd rect
			(at 2.050034 -38.675056 90)
			(size 0.519938 1.4986)
			(layers "F.Cu" "F.Mask" "F.Paste")
			(net "M_L_CPU1_SA_DQ<18>")
		)
		(pad "175" smd rect
			(at 2.050034 -37.824918 90)
			(size 0.519938 1.4986)
			(layers "F.Cu" "F.Mask" "F.Paste")
			(net "GND")
		)
		(pad "176" smd rect
			(at 2.050034 -36.975034 90)
			(size 0.519938 1.4986)
			(layers "F.Cu" "F.Mask" "F.Paste")
			(net "M_L_CPU1_SA_DQ<19>")
		)
		(pad "177" smd rect
			(at 2.050034 -36.124896 90)
			(size 0.519938 1.4986)
			(layers "F.Cu" "F.Mask" "F.Paste")
			(net "GND")
		)
		(pad "178" smd rect
			(at 2.050034 -35.275012 90)
			(size 0.519938 1.4986)
			(layers "F.Cu" "F.Mask" "F.Paste")
			(net "M_L_CPU1_SA_DQS_DN<7>")
		)
		(pad "179" smd rect
			(at 2.050034 -34.425128 90)
			(size 0.519938 1.4986)
			(layers "F.Cu" "F.Mask" "F.Paste")
			(net "M_L_CPU1_SA_DQS_DP<7>")
		)
		(pad "180" smd rect
			(at 2.050034 -33.57499 90)
			(size 0.519938 1.4986)
			(layers "F.Cu" "F.Mask" "F.Paste")
			(net "GND")
		)
		(pad "181" smd rect
			(at 2.050034 -32.725106 90)
			(size 0.519938 1.4986)
			(layers "F.Cu" "F.Mask" "F.Paste")
			(net "M_L_CPU1_SA_DQ<22>")
		)
		(pad "182" smd rect
			(at 2.050034 -31.874968 90)
			(size 0.519938 1.4986)
			(layers "F.Cu" "F.Mask" "F.Paste")
			(net "GND")
		)
		(pad "183" smd rect
			(at 2.050034 -31.025084 90)
			(size 0.519938 1.4986)
			(layers "F.Cu" "F.Mask" "F.Paste")
			(net "M_L_CPU1_SA_DQ<23>")
		)
		(pad "184" smd rect
			(at 2.050034 -30.174946 90)
			(size 0.519938 1.4986)
			(layers "F.Cu" "F.Mask" "F.Paste")
			(net "GND")
		)
		(pad "185" smd rect
			(at 2.050034 -29.325062 90)
			(size 0.519938 1.4986)
			(layers "F.Cu" "F.Mask" "F.Paste")
			(net "M_L_CPU1_SA_DQ<26>")
		)
		(pad "186" smd rect
			(at 2.050034 -28.474924 90)
			(size 0.519938 1.4986)
			(layers "F.Cu" "F.Mask" "F.Paste")
			(net "GND")
		)
		(pad "187" smd rect
			(at 2.050034 -27.62504 90)
			(size 0.519938 1.4986)
			(layers "F.Cu" "F.Mask" "F.Paste")
			(net "M_L_CPU1_SA_DQ<27>")
		)
		(pad "188" smd rect
			(at 2.050034 -26.774902 90)
			(size 0.519938 1.4986)
			(layers "F.Cu" "F.Mask" "F.Paste")
			(net "GND")
		)
		(pad "189" smd rect
			(at 2.050034 -25.925018 90)
			(size 0.519938 1.4986)
			(layers "F.Cu" "F.Mask" "F.Paste")
			(net "M_L_CPU1_SA_DQS_DN<8>")
		)
		(pad "190" smd rect
			(at 2.050034 -25.07488 90)
			(size 0.519938 1.4986)
			(layers "F.Cu" "F.Mask" "F.Paste")
			(net "M_L_CPU1_SA_DQS_DP<8>")
		)
		(pad "191" smd rect
			(at 2.050034 -24.224996 90)
			(size 0.519938 1.4986)
			(layers "F.Cu" "F.Mask" "F.Paste")
			(net "GND")
		)
		(pad "192" smd rect
			(at 2.050034 -23.375112 90)
			(size 0.519938 1.4986)
			(layers "F.Cu" "F.Mask" "F.Paste")
			(net "M_L_CPU1_SA_DQ<30>")
		)
		(pad "193" smd rect
			(at 2.050034 -22.524974 90)
			(size 0.519938 1.4986)
			(layers "F.Cu" "F.Mask" "F.Paste")
			(net "GND")
		)
		(pad "194" smd rect
			(at 2.050034 -21.67509 90)
			(size 0.519938 1.4986)
			(layers "F.Cu" "F.Mask" "F.Paste")
			(net "M_L_CPU1_SA_DQ<31>")
		)
		(pad "195" smd rect
			(at 2.050034 -20.824952 90)
			(size 0.519938 1.4986)
			(layers "F.Cu" "F.Mask" "F.Paste")
			(net "GND")
		)
		(pad "196" smd rect
			(at 2.050034 -19.975068 90)
			(size 0.519938 1.4986)
			(layers "F.Cu" "F.Mask" "F.Paste")
			(net "M_L_CPU1_SA_CB<2>")
		)
		(pad "197" smd rect
			(at 2.050034 -19.12493 90)
			(size 0.519938 1.4986)
			(layers "F.Cu" "F.Mask" "F.Paste")
			(net "GND")
		)
		(pad "198" smd rect
			(at 2.050034 -18.275046 90)
			(size 0.519938 1.4986)
			(layers "F.Cu" "F.Mask" "F.Paste")
			(net "M_L_CPU1_SA_CB<3>")
		)
		(pad "199" smd rect
			(at 2.050034 -17.424908 90)
			(size 0.519938 1.4986)
			(layers "F.Cu" "F.Mask" "F.Paste")
			(net "GND")
		)
		(pad "200" smd rect
			(at 2.050034 -16.575024 90)
			(size 0.519938 1.4986)
			(layers "F.Cu" "F.Mask" "F.Paste")
			(net "M_L_CPU1_SA_DQS_DN<9>")
		)
		(pad "201" smd rect
			(at 2.050034 -15.724886 90)
			(size 0.519938 1.4986)
			(layers "F.Cu" "F.Mask" "F.Paste")
			(net "M_L_CPU1_SA_DQS_DP<9>")
		)
		(pad "202" smd rect
			(at 2.050034 -14.875002 90)
			(size 0.519938 1.4986)
			(layers "F.Cu" "F.Mask" "F.Paste")
			(net "GND")
		)
		(pad "203" smd rect
			(at 2.050034 -14.025118 90)
			(size 0.519938 1.4986)
			(layers "F.Cu" "F.Mask" "F.Paste")
			(net "M_L_CPU1_SA_CB<6>")
		)
		(pad "204" smd rect
			(at 2.050034 -13.17498 90)
			(size 0.519938 1.4986)
			(layers "F.Cu" "F.Mask" "F.Paste")
			(net "GND")
		)
		(pad "205" smd rect
			(at 2.050034 -12.325096 90)
			(size 0.519938 1.4986)
			(layers "F.Cu" "F.Mask" "F.Paste")
			(net "M_L_CPU1_SA_CB<7>")
		)
		(pad "206" smd rect
			(at 2.050034 -11.474958 90)
			(size 0.519938 1.4986)
			(layers "F.Cu" "F.Mask" "F.Paste")
			(net "GND")
		)
		(pad "207" smd rect
			(at 2.050034 -10.625074 90)
			(size 0.519938 1.4986)
			(layers "F.Cu" "F.Mask" "F.Paste")
			(net "M_L_CPU1_RESET_N")
		)
		(pad "208" smd rect
			(at 2.050034 -9.774936 90)
			(size 0.519938 1.4986)
			(layers "F.Cu" "F.Mask" "F.Paste")
			(net "GND")
		)
		(pad "209" smd rect
			(at 2.050034 -8.925052 90)
			(size 0.519938 1.4986)
			(layers "F.Cu" "F.Mask" "F.Paste")
			(net "M_L_CPU1_SA_CS_N<1>")
		)
		(pad "210" smd rect
			(at 2.050034 -8.074914 90)
			(size 0.519938 1.4986)
			(layers "F.Cu" "F.Mask" "F.Paste")
			(net "GND")
		)
		(pad "211" smd rect
			(at 2.050034 -7.22503 90)
			(size 0.519938 1.4986)
			(layers "F.Cu" "F.Mask" "F.Paste")
			(net "M_L_CPU1_SA_CA<1>")
		)
		(pad "212" smd rect
			(at 2.050034 -6.374892 90)
			(size 0.519938 1.4986)
			(layers "F.Cu" "F.Mask" "F.Paste")
			(net "GND")
		)
		(pad "213" smd rect
			(at 2.050034 -5.525008 90)
			(size 0.519938 1.4986)
			(layers "F.Cu" "F.Mask" "F.Paste")
			(net "M_L_CPU1_SA_CA<3>")
		)
		(pad "214" smd rect
			(at 2.050034 -4.675124 90)
			(size 0.519938 1.4986)
			(layers "F.Cu" "F.Mask" "F.Paste")
			(net "GND")
		)
		(pad "215" smd rect
			(at 2.050034 -3.824986 90)
			(size 0.519938 1.4986)
			(layers "F.Cu" "F.Mask" "F.Paste")
			(net "M_L_CPU1_SA_CA<5>")
		)
		(pad "216" smd rect
			(at 2.050034 -2.975102 90)
			(size 0.519938 1.4986)
			(layers "F.Cu" "F.Mask" "F.Paste")
			(net "GND")
		)
		(pad "217" smd rect
			(at 2.050034 -2.124964 90)
			(size 0.519938 1.4986)
			(layers "F.Cu" "F.Mask" "F.Paste")
			(net "M_L_CPU1_CLK_DP<0>")
		)
		(pad "218" smd rect
			(at 2.050034 -1.27508 90)
			(size 0.519938 1.4986)
			(layers "F.Cu" "F.Mask" "F.Paste")
			(net "M_L_CPU1_CLK_DN<0>")
		)
		(pad "219" smd rect
			(at 2.050034 -0.424942 90)
			(size 0.519938 1.4986)
			(layers "F.Cu" "F.Mask" "F.Paste")
			(net "GND")
		)
		(pad "220" smd rect
			(at 2.050034 5.525008 90)
			(size 0.519938 1.4986)
			(layers "F.Cu" "F.Mask" "F.Paste")
			(net "Net_2414")
		)
		(pad "221" smd rect
			(at 2.050034 6.374892 90)
			(size 0.519938 1.4986)
			(layers "F.Cu" "F.Mask" "F.Paste")
			(net "M_L_CPU1_SB_CA<1>")
		)
		(pad "222" smd rect
			(at 2.050034 7.22503 90)
			(size 0.519938 1.4986)
			(layers "F.Cu" "F.Mask" "F.Paste")
			(net "GND")
		)
		(pad "223" smd rect
			(at 2.050034 8.074914 90)
			(size 0.519938 1.4986)
			(layers "F.Cu" "F.Mask" "F.Paste")
			(net "M_L_CPU1_SB_CA<3>")
		)
		(pad "224" smd rect
			(at 2.050034 8.925052 90)
			(size 0.519938 1.4986)
			(layers "F.Cu" "F.Mask" "F.Paste")
			(net "GND")
		)
		(pad "225" smd rect
			(at 2.050034 9.774936 90)
			(size 0.519938 1.4986)
			(layers "F.Cu" "F.Mask" "F.Paste")
			(net "M_L_CPU1_SB_CA<5>")
		)
		(pad "226" smd rect
			(at 2.050034 10.625074 90)
			(size 0.519938 1.4986)
			(layers "F.Cu" "F.Mask" "F.Paste")
			(net "GND")
		)
	)
)
